(kicad_pcb
	(version 20260206)
	(generator "pcbnew")
	(generator_version "10.0")
	(general
		(thickness 1.6)
		(legacy_teardrops no)
	)
	(paper "A4")
	(title_block
		(title "Bryce Canyon_SCC_16316-1_OCP.brd")
		(comment 1 "Bryce Canyon / footprints 1432-1438 of 1561")
	)
	(layers
		(0 "F.Cu" signal "TOP")
		(4 "In1.Cu" signal "L2GND")
		(6 "In2.Cu" signal "L3")
		(8 "In3.Cu" signal "L4VCC")
		(10 "In4.Cu" signal "L5VCC")
		(12 "In5.Cu" signal "L6")
		(14 "In6.Cu" signal "L7GND")
		(2 "B.Cu" signal "BOTTOM")
		(9 "F.Adhes" user "F.Adhesive")
		(11 "B.Adhes" user "B.Adhesive")
		(13 "F.Paste" user "Package Geometry/Pastemask Top")
		(15 "B.Paste" user "Package Geometry/Pastemask Bottom")
		(5 "F.SilkS" user "Ref Des/Silkscreen Top")
		(7 "B.SilkS" user "Ref Des/Silkscreen Bottom")
		(1 "F.Mask" user "Board Geometry/Soldermask Top")
		(3 "B.Mask" user "Board Geometry/Soldermask Bottom")
		(17 "Dwgs.User" user "User.Drawings")
		(19 "Cmts.User" user "User.Comments")
		(21 "Eco1.User" user "User.Eco1")
		(23 "Eco2.User" user "User.Eco2")
		(25 "Edge.Cuts" user "Board Geometry/Outline")
		(27 "Margin" user)
		(31 "F.CrtYd" user "Package Geometry/Place Bound Top")
		(29 "B.CrtYd" user "Package Geometry/Place Bound Bottom")
		(35 "F.Fab" user "Ref Des/Assembly Top")
		(33 "B.Fab" user "Ref Des/Assembly Bottom")
	)
	(footprint ""
		(layer "B.Cu")
		(at 41.157652 -112.556544)
		(property "Reference" "U7"
			(at 0 0 0)
			(layer "B.SilkS")
			(hide yes)
			(effects
				(font
					(size 1.27 1.27)
				)
				(justify mirror)
			)
		)
		(property "Value" "UA78M05CDCYRG3-GP"
			(at 0 -16.2052 0)
			(unlocked yes)
			(layer "B.Fab")
			(hide yes)
			(effects
				(font
					(size 1.016 1.016)
					(thickness 0.1524)
				)
				(justify mirror)
			)
		)
		(property "Device Type" "SOT-223H67"
			(at 0 -17.7292 0)
			(unlocked yes)
			(layer "B.Fab")
			(hide yes)
			(effects
				(font
					(size 1.016 1.016)
					(thickness 0.1524)
				)
				(justify mirror)
			)
		)
		(duplicate_pad_numbers_are_jumpers no)
		(fp_line
			(start -3.683 -7.366)
			(end 3.683 -7.366)
			(stroke
				(width 0.1524)
				(type default)
			)
			(layer "B.SilkS")
		)
		(fp_line
			(start -3.683 1.524)
			(end -3.683 -7.366)
			(stroke
				(width 0.1524)
				(type default)
			)
			(layer "B.SilkS")
		)
		(fp_line
			(start 3.683 -7.366)
			(end 3.683 1.524)
			(stroke
				(width 0.1524)
				(type default)
			)
			(layer "B.SilkS")
		)
		(fp_line
			(start 3.683 1.524)
			(end -3.683 1.524)
			(stroke
				(width 0.1524)
				(type default)
			)
			(layer "B.SilkS")
		)
		(fp_line
			(start 3.7592 0.3556)
			(end 3.7592 1.6256)
			(stroke
				(width 0.3302)
				(type default)
			)
			(layer "B.SilkS")
		)
		(fp_line
			(start 3.7592 1.6256)
			(end 2.4892 1.6256)
			(stroke
				(width 0.3302)
				(type default)
			)
			(layer "B.SilkS")
		)
		(fp_poly
			(pts
				(xy 0.635 -1.016) (xy -0.635 -1.016) (xy -0.635 1.016) (xy 0.635 1.016)
			)
			(stroke
				(width 0)
				(type default)
			)
			(fill yes)
			(layer "B.Paste")
		)
		(fp_poly
			(pts
				(xy 1.778 -6.731) (xy -1.778 -6.731) (xy -1.778 -4.699) (xy 1.778 -4.699)
			)
			(stroke
				(width 0)
				(type default)
			)
			(fill yes)
			(layer "B.Paste")
		)
		(fp_poly
			(pts
				(xy 3.683 1.524) (xy -3.683 1.524) (xy -3.683 -7.366) (xy 3.683 -7.366)
			)
			(stroke
				(width 0)
				(type default)
			)
			(fill no)
			(layer "B.CrtYd")
		)
		(fp_poly
			(pts
				(xy 3.683 -7.366) (xy -3.683 -7.366) (xy -3.683 1.524) (xy 3.683 1.524)
			)
			(stroke
				(width 0)
				(type default)
			)
			(fill no)
			(layer "B.Fab")
		)
		(pad "1" smd rect
			(at 2.286 0 180)
			(size 1.27 2.032)
			(layers "B.Cu" "B.Mask" "B.Paste")
			(net "P12V_STBY_SCC")
		)
		(pad "2" smd custom
			(at 0 0 180)
			(size 0.889 0.889)
			(layers "B.Cu" "B.Mask" "B.Paste")
			(net "GND")
			(options
				(clearance outline)
				(anchor circle)
			)
			(primitives
				(gr_poly
					(pts
						(xy -1.778 3.8735) (xy 1.778 3.8735) (xy 1.778 1.8415) (xy 0.381 1.8415) (xy 0.381 -1.8415) (xy 0.635 -1.8415)
						(xy 0.635 -3.8735) (xy -0.635 -3.8735) (xy -0.635 -1.8415) (xy -0.381 -1.8415) (xy -0.381 1.8415)
						(xy -1.778 1.8415)
					)
					(width 0)
					(fill yes)
				)
			)
		)
		(pad "3" smd rect
			(at -2.286 0 180)
			(size 1.27 2.032)
			(layers "B.Cu" "B.Mask" "B.Paste")
			(net "P5V")
		)
	)
	(footprint ""
		(layer "B.Cu")
		(at 157.740604 -59.677808 90)
		(property "Reference" "C362"
			(at 0 0 90)
			(layer "B.SilkS")
			(hide yes)
			(effects
				(font
					(size 1.27 1.27)
				)
				(justify mirror)
			)
		)
		(property "Value" "SCD1U16V2KX-3GP"
			(at -1.1811 -2.7051 90)
			(unlocked yes)
			(layer "B.Fab")
			(hide yes)
			(effects
				(font
					(size 1.016 1.016)
					(thickness 0.1524)
				)
				(justify mirror)
			)
		)
		(property "Device Type" "C402H22"
			(at -1.1811 -4.2291 90)
			(unlocked yes)
			(layer "B.Fab")
			(hide yes)
			(effects
				(font
					(size 1.016 1.016)
					(thickness 0.1524)
				)
				(justify mirror)
			)
		)
		(duplicate_pad_numbers_are_jumpers no)
		(fp_rect
			(start 0.4318 0.9525)
			(end -0.4318 -0.9525)
			(stroke
				(width 0)
				(type default)
			)
			(fill no)
			(layer "B.CrtYd")
		)
		(fp_rect
			(start 0.4318 0.9525)
			(end -0.4318 -0.9525)
			(stroke
				(width 0)
				(type default)
			)
			(fill no)
			(layer "B.Fab")
		)
		(pad "1" smd custom
			(at 0 -0.4445 270)
			(size 0.1524 0.1524)
			(layers "B.Cu" "B.Mask" "B.Paste")
			(net "SHELL_PLL_VDD")
			(options
				(clearance outline)
				(anchor circle)
			)
			(primitives
				(gr_poly
					(pts
						(arc
							(start 0.3048 0.2032)
							(mid 0.275042 0.275042)
							(end 0.2032 0.3048)
						)
						(arc
							(start -0.2032 0.3048)
							(mid -0.275042 0.275042)
							(end -0.3048 0.2032)
						)
						(arc
							(start -0.3048 -0.2032)
							(mid -0.275042 -0.275042)
							(end -0.2032 -0.3048)
						)
						(arc
							(start 0.2032 -0.3048)
							(mid 0.275042 -0.275042)
							(end 0.3048 -0.2032)
						)
					)
					(width 0)
					(fill yes)
				)
			)
		)
		(pad "2" smd custom
			(at 0 0.4445 270)
			(size 0.1524 0.1524)
			(layers "B.Cu" "B.Mask" "B.Paste")
			(net "GND")
			(options
				(clearance outline)
				(anchor circle)
			)
			(primitives
				(gr_poly
					(pts
						(arc
							(start 0.3048 0.2032)
							(mid 0.275042 0.275042)
							(end 0.2032 0.3048)
						)
						(arc
							(start -0.2032 0.3048)
							(mid -0.275042 0.275042)
							(end -0.3048 0.2032)
						)
						(arc
							(start -0.3048 -0.2032)
							(mid -0.275042 -0.275042)
							(end -0.2032 -0.3048)
						)
						(arc
							(start 0.2032 -0.3048)
							(mid 0.275042 -0.275042)
							(end 0.3048 -0.2032)
						)
					)
					(width 0)
					(fill yes)
				)
			)
		)
	)
	(footprint ""
		(layer "B.Cu")
		(at 177.673 -30.353 -90)
		(property "Reference" "C485"
			(at 0 0 90)
			(layer "B.SilkS")
			(hide yes)
			(effects
				(font
					(size 1.27 1.27)
				)
				(justify mirror)
			)
		)
		(property "Value" "SC1U16V2KX-7-GP"
			(at -1.7526 -1.6002 270)
			(unlocked yes)
			(layer "B.Fab")
			(hide yes)
			(effects
				(font
					(size 1.016 1.016)
					(thickness 0.1524)
				)
				(justify mirror)
			)
		)
		(property "Device Type" "C402-TO0D2H24"
			(at -1.7526 -3.1242 270)
			(unlocked yes)
			(layer "B.Fab")
			(hide yes)
			(effects
				(font
					(size 1.016 1.016)
					(thickness 0.1524)
				)
				(justify mirror)
			)
		)
		(duplicate_pad_numbers_are_jumpers no)
		(fp_rect
			(start 0.4826 0.889)
			(end -0.4826 -0.889)
			(stroke
				(width 0)
				(type default)
			)
			(fill no)
			(layer "B.CrtYd")
		)
		(fp_rect
			(start 0.4826 0.889)
			(end -0.4826 -0.889)
			(stroke
				(width 0)
				(type default)
			)
			(fill no)
			(layer "B.Fab")
		)
		(pad "1" smd custom
			(at 0 -0.4572 90)
			(size 0.1524 0.1524)
			(layers "B.Cu" "B.Mask" "B.Paste")
			(net "P1V8_C")
			(options
				(clearance outline)
				(anchor circle)
			)
			(primitives
				(gr_poly
					(pts
						(arc
							(start -0.254 -0.3048)
							(mid -0.325842 -0.275042)
							(end -0.3556 -0.2032)
						)
						(arc
							(start -0.3556 0.2032)
							(mid -0.325842 0.275042)
							(end -0.254 0.3048)
						)
						(arc
							(start 0.254 0.3048)
							(mid 0.325842 0.275042)
							(end 0.3556 0.2032)
						)
						(arc
							(start 0.3556 -0.2032)
							(mid 0.325842 -0.275042)
							(end 0.254 -0.3048)
						)
					)
					(width 0)
					(fill yes)
				)
			)
		)
		(pad "2" smd custom
			(at 0 0.4572 90)
			(size 0.1524 0.1524)
			(layers "B.Cu" "B.Mask" "B.Paste")
			(net "GND")
			(options
				(clearance outline)
				(anchor circle)
			)
			(primitives
				(gr_poly
					(pts
						(arc
							(start -0.254 -0.3048)
							(mid -0.325842 -0.275042)
							(end -0.3556 -0.2032)
						)
						(arc
							(start -0.3556 0.2032)
							(mid -0.325842 0.275042)
							(end -0.254 0.3048)
						)
						(arc
							(start 0.254 0.3048)
							(mid 0.325842 0.275042)
							(end 0.3556 0.2032)
						)
						(arc
							(start 0.3556 -0.2032)
							(mid 0.325842 -0.275042)
							(end 0.254 -0.3048)
						)
					)
					(width 0)
					(fill yes)
				)
			)
		)
	)
	(footprint ""
		(layer "B.Cu")
		(at 183.2356 -30.353 90)
		(property "Reference" "C483"
			(at 0 0 90)
			(layer "B.SilkS")
			(hide yes)
			(effects
				(font
					(size 1.27 1.27)
				)
				(justify mirror)
			)
		)
		(property "Value" "SC1U16V2KX-7-GP"
			(at -1.7526 -1.6002 90)
			(unlocked yes)
			(layer "B.Fab")
			(hide yes)
			(effects
				(font
					(size 1.016 1.016)
					(thickness 0.1524)
				)
				(justify mirror)
			)
		)
		(property "Device Type" "C402-TO0D2H24"
			(at -1.7526 -3.1242 90)
			(unlocked yes)
			(layer "B.Fab")
			(hide yes)
			(effects
				(font
					(size 1.016 1.016)
					(thickness 0.1524)
				)
				(justify mirror)
			)
		)
		(duplicate_pad_numbers_are_jumpers no)
		(fp_rect
			(start 0.4826 0.889)
			(end -0.4826 -0.889)
			(stroke
				(width 0)
				(type default)
			)
			(fill no)
			(layer "B.CrtYd")
		)
		(fp_rect
			(start 0.4826 0.889)
			(end -0.4826 -0.889)
			(stroke
				(width 0)
				(type default)
			)
			(fill no)
			(layer "B.Fab")
		)
		(pad "1" smd custom
			(at 0 -0.4572 270)
			(size 0.1524 0.1524)
			(layers "B.Cu" "B.Mask" "B.Paste")
			(net "P1V8_C")
			(options
				(clearance outline)
				(anchor circle)
			)
			(primitives
				(gr_poly
					(pts
						(arc
							(start -0.254 -0.3048)
							(mid -0.325842 -0.275042)
							(end -0.3556 -0.2032)
						)
						(arc
							(start -0.3556 0.2032)
							(mid -0.325842 0.275042)
							(end -0.254 0.3048)
						)
						(arc
							(start 0.254 0.3048)
							(mid 0.325842 0.275042)
							(end 0.3556 0.2032)
						)
						(arc
							(start 0.3556 -0.2032)
							(mid 0.325842 -0.275042)
							(end 0.254 -0.3048)
						)
					)
					(width 0)
					(fill yes)
				)
			)
		)
		(pad "2" smd custom
			(at 0 0.4572 270)
			(size 0.1524 0.1524)
			(layers "B.Cu" "B.Mask" "B.Paste")
			(net "GND")
			(options
				(clearance outline)
				(anchor circle)
			)
			(primitives
				(gr_poly
					(pts
						(arc
							(start -0.254 -0.3048)
							(mid -0.325842 -0.275042)
							(end -0.3556 -0.2032)
						)
						(arc
							(start -0.3556 0.2032)
							(mid -0.325842 0.275042)
							(end -0.254 0.3048)
						)
						(arc
							(start 0.254 0.3048)
							(mid 0.325842 0.275042)
							(end 0.3556 0.2032)
						)
						(arc
							(start 0.3556 -0.2032)
							(mid 0.325842 -0.275042)
							(end 0.254 -0.3048)
						)
					)
					(width 0)
					(fill yes)
				)
			)
		)
	)
	(footprint ""
		(layer "B.Cu")
		(at 163.1696 -60.5536 -90)
		(property "Reference" "C370"
			(at 0 0 90)
			(layer "B.SilkS")
			(hide yes)
			(effects
				(font
					(size 1.27 1.27)
				)
				(justify mirror)
			)
		)
		(property "Value" "SCD1U16V2KX-3GP"
			(at -1.1811 -2.7051 270)
			(unlocked yes)
			(layer "B.Fab")
			(hide yes)
			(effects
				(font
					(size 1.016 1.016)
					(thickness 0.1524)
				)
				(justify mirror)
			)
		)
		(property "Device Type" "C402H22"
			(at -1.1811 -4.2291 270)
			(unlocked yes)
			(layer "B.Fab")
			(hide yes)
			(effects
				(font
					(size 1.016 1.016)
					(thickness 0.1524)
				)
				(justify mirror)
			)
		)
		(duplicate_pad_numbers_are_jumpers no)
		(fp_rect
			(start 0.4318 0.9525)
			(end -0.4318 -0.9525)
			(stroke
				(width 0)
				(type default)
			)
			(fill no)
			(layer "B.CrtYd")
		)
		(fp_rect
			(start 0.4318 0.9525)
			(end -0.4318 -0.9525)
			(stroke
				(width 0)
				(type default)
			)
			(fill no)
			(layer "B.Fab")
		)
		(pad "1" smd custom
			(at 0 -0.4445 90)
			(size 0.1524 0.1524)
			(layers "B.Cu" "B.Mask" "B.Paste")
			(net "VDDA_SAS_REF_CLK")
			(options
				(clearance outline)
				(anchor circle)
			)
			(primitives
				(gr_poly
					(pts
						(arc
							(start 0.3048 0.2032)
							(mid 0.275042 0.275042)
							(end 0.2032 0.3048)
						)
						(arc
							(start -0.2032 0.3048)
							(mid -0.275042 0.275042)
							(end -0.3048 0.2032)
						)
						(arc
							(start -0.3048 -0.2032)
							(mid -0.275042 -0.275042)
							(end -0.2032 -0.3048)
						)
						(arc
							(start 0.2032 -0.3048)
							(mid 0.275042 -0.275042)
							(end 0.3048 -0.2032)
						)
					)
					(width 0)
					(fill yes)
				)
			)
		)
		(pad "2" smd custom
			(at 0 0.4445 90)
			(size 0.1524 0.1524)
			(layers "B.Cu" "B.Mask" "B.Paste")
			(net "GND")
			(options
				(clearance outline)
				(anchor circle)
			)
			(primitives
				(gr_poly
					(pts
						(arc
							(start 0.3048 0.2032)
							(mid 0.275042 0.275042)
							(end 0.2032 0.3048)
						)
						(arc
							(start -0.2032 0.3048)
							(mid -0.275042 0.275042)
							(end -0.3048 0.2032)
						)
						(arc
							(start -0.3048 -0.2032)
							(mid -0.275042 -0.275042)
							(end -0.2032 -0.3048)
						)
						(arc
							(start 0.2032 -0.3048)
							(mid 0.275042 -0.275042)
							(end 0.3048 -0.2032)
						)
					)
					(width 0)
					(fill yes)
				)
			)
		)
	)
	(footprint ""
		(layer "B.Cu")
		(at 108.8517 -59.4487)
		(property "Reference" "C239"
			(at 0 0 0)
			(layer "B.SilkS")
			(hide yes)
			(effects
				(font
					(size 1.27 1.27)
				)
				(justify mirror)
			)
		)
		(property "Value" "SCD1U6D3V1KX-GP"
			(at 2.8321 -1.7399 0)
			(unlocked yes)
			(layer "B.Fab")
			(hide yes)
			(effects
				(font
					(size 1.016 1.016)
					(thickness 0.1524)
				)
				(justify mirror)
			)
		)
		(property "Device Type" "C0201H13"
			(at 2.8321 -3.2639 0)
			(unlocked yes)
			(layer "B.Fab")
			(hide yes)
			(effects
				(font
					(size 1.016 1.016)
					(thickness 0.1524)
				)
				(justify mirror)
			)
		)
		(duplicate_pad_numbers_are_jumpers no)
		(fp_rect
			(start 0.2794 0.6477)
			(end -0.2794 -0.6477)
			(stroke
				(width 0)
				(type default)
			)
			(fill no)
			(layer "B.CrtYd")
		)
		(fp_rect
			(start 0.2794 0.6477)
			(end -0.2794 -0.6477)
			(stroke
				(width 0)
				(type default)
			)
			(fill no)
			(layer "B.Fab")
		)
		(pad "1" smd custom
			(at 0 -0.2794 180)
			(size 0.0762 0.0762)
			(layers "B.Cu" "B.Mask" "B.Paste")
			(net "GB_VDDA")
			(options
				(clearance outline)
				(anchor circle)
			)
			(primitives
				(gr_poly
					(pts
						(arc
							(start 0.1524 0.127)
							(mid 0.137521 0.162921)
							(end 0.1016 0.1778)
						)
						(arc
							(start -0.1016 0.1778)
							(mid -0.137521 0.162921)
							(end -0.1524 0.127)
						)
						(arc
							(start -0.1524 -0.127)
							(mid -0.137521 -0.162921)
							(end -0.1016 -0.1778)
						)
						(arc
							(start 0.1016 -0.1778)
							(mid 0.137521 -0.162921)
							(end 0.1524 -0.127)
						)
					)
					(width 0)
					(fill yes)
				)
			)
		)
		(pad "2" smd custom
			(at 0 0.2794 180)
			(size 0.0762 0.0762)
			(layers "B.Cu" "B.Mask" "B.Paste")
			(net "GND")
			(options
				(clearance outline)
				(anchor circle)
			)
			(primitives
				(gr_poly
					(pts
						(arc
							(start 0.1524 0.127)
							(mid 0.137521 0.162921)
							(end 0.1016 0.1778)
						)
						(arc
							(start -0.1016 0.1778)
							(mid -0.137521 0.162921)
							(end -0.1524 0.127)
						)
						(arc
							(start -0.1524 -0.127)
							(mid -0.137521 -0.162921)
							(end -0.1016 -0.1778)
						)
						(arc
							(start 0.1016 -0.1778)
							(mid 0.137521 -0.162921)
							(end 0.1524 -0.127)
						)
					)
					(width 0)
					(fill yes)
				)
			)
		)
	)
	(footprint ""
		(layer "B.Cu")
		(at 132.466588 -87.260684 180)
		(property "Reference" "R42"
			(at 0 0 0)
			(layer "B.SilkS")
			(hide yes)
			(effects
				(font
					(size 1.27 1.27)
				)
				(justify mirror)
			)
		)
		(property "Value" "4K7R2F-GP"
			(at -0.064008 -3.993896 180)
			(unlocked yes)
			(layer "B.Fab")
			(hide yes)
			(effects
				(font
					(size 1.016 1.016)
					(thickness 0.1524)
				)
				(justify mirror)
			)
		)
		(property "Device Type" "R402H16"
			(at -0.064008 -5.517896 180)
			(unlocked yes)
			(layer "B.Fab")
			(hide yes)
			(effects
				(font
					(size 1.016 1.016)
					(thickness 0.1524)
				)
				(justify mirror)
			)
		)
		(duplicate_pad_numbers_are_jumpers no)
		(fp_line
			(start 0.508 -0.9398)
			(end 0.508 0.9398)
			(stroke
				(width 0.1524)
				(type default)
			)
			(layer "B.SilkS")
		)
		(fp_line
			(start -0.508 -0.9398)
			(end 0.508 -0.9398)
			(stroke
				(width 0.1524)
				(type default)
			)
			(layer "B.SilkS")
		)
		(fp_rect
			(start 0.508 0.9398)
			(end -0.508 -0.9398)
			(stroke
				(width 0)
				(type default)
			)
			(fill no)
			(layer "B.CrtYd")
		)
		(fp_rect
			(start 0.508 0.9398)
			(end -0.508 -0.9398)
			(stroke
				(width 0)
				(type default)
			)
			(fill no)
			(layer "B.Fab")
		)
		(pad "1" smd custom
			(at 0 -0.4445)
			(size 0.1397 0.1397)
			(layers "B.Cu" "B.Mask" "B.Paste")
			(net "EXP_SIO_CLK_OUT")
			(options
				(clearance outline)
				(anchor circle)
			)
			(primitives
				(gr_poly
					(pts
						(arc
							(start -0.1778 0.2794)
							(mid -0.249642 0.249642)
							(end -0.2794 0.1778)
						)
						(arc
							(start -0.2794 -0.1778)
							(mid -0.249642 -0.249642)
							(end -0.1778 -0.2794)
						)
						(arc
							(start 0.1778 -0.2794)
							(mid 0.249642 -0.249642)
							(end 0.2794 -0.1778)
						)
						(arc
							(start 0.2794 0.1778)
							(mid 0.249642 0.249642)
							(end 0.1778 0.2794)
						)
					)
					(width 0)
					(fill yes)
				)
			)
		)
		(pad "2" smd custom
			(at 0 0.4445)
			(size 0.1397 0.1397)
			(layers "B.Cu" "B.Mask" "B.Paste")
			(net "P1V8_E")
			(options
				(clearance outline)
				(anchor circle)
			)
			(primitives
				(gr_poly
					(pts
						(arc
							(start -0.1778 0.2794)
							(mid -0.249642 0.249642)
							(end -0.2794 0.1778)
						)
						(arc
							(start -0.2794 -0.1778)
							(mid -0.249642 -0.249642)
							(end -0.1778 -0.2794)
						)
						(arc
							(start 0.1778 -0.2794)
							(mid 0.249642 -0.249642)
							(end 0.2794 -0.1778)
						)
						(arc
							(start 0.2794 0.1778)
							(mid 0.249642 0.249642)
							(end 0.1778 0.2794)
						)
					)
					(width 0)
					(fill yes)
				)
			)
		)
	)
)
